(kicad_pcb
	(version 20241229)
	(generator "pcbnew")
	(generator_version "9.0")
	(general
		(thickness 1.62)
		(legacy_teardrops no)
	)
	(paper "A3")
	(title_block
		(title "COM Express 7 Baseboard")
		(date "2025-02-04")
		(rev "1.1.2")
		(company "Antmicro Ltd")
		(comment 1 "www.antmicro.com")
		(comment 9 "footprints 556-559 of 802")
	)
	(layers
		(0 "F.Cu" signal)
		(4 "In1.Cu" signal)
		(6 "In2.Cu" signal)
		(8 "In3.Cu" signal)
		(10 "In4.Cu" signal)
		(12 "In5.Cu" signal)
		(14 "In6.Cu" signal)
		(2 "B.Cu" signal)
		(9 "F.Adhes" user "F.Adhesive")
		(11 "B.Adhes" user "B.Adhesive")
		(13 "F.Paste" user)
		(15 "B.Paste" user)
		(5 "F.SilkS" user "F.Silkscreen")
		(7 "B.SilkS" user "B.Silkscreen")
		(1 "F.Mask" user)
		(3 "B.Mask" user)
		(17 "Dwgs.User" user "User.Drawings")
		(19 "Cmts.User" user "User.Comments")
		(21 "Eco1.User" user "User.Eco1")
		(23 "Eco2.User" user "User.Eco2")
		(25 "Edge.Cuts" user)
		(27 "Margin" user)
		(31 "F.CrtYd" user "F.Courtyard")
		(29 "B.CrtYd" user "B.Courtyard")
		(35 "F.Fab" user)
		(33 "B.Fab" user)
	)
	(footprint "antmicro-footprints:R_0402_1005Metric"
		(layer "B.Cu")
		(at 121.7 162.56)
		(descr "Resistor SMD 0402")
		(tags "resistor SMD 0402")
		(property "Reference" "R78"
			(at 0.85 0.45 0)
			(layer "B.SilkS")
			(effects
				(font
					(size 0.7 0.7)
					(thickness 0.15)
				)
				(justify right bottom mirror)
			)
		)
		(property "Value" "R_10k_0402"
			(at -1.011843 -1.772047 0)
			(layer "B.Fab")
			(effects
				(font
					(size 0.7 0.7)
					(thickness 0.15)
				)
				(justify right bottom mirror)
			)
		)
		(property "Datasheet" "https://www.bourns.com/docs/product-datasheets/cr.pdf"
			(at 0 0 0)
			(layer "F.Fab")
			(hide yes)
			(effects
				(font
					(size 1.27 1.27)
					(thickness 0.15)
				)
			)
		)
		(property "Author" "Antmicro"
			(at 0 0 0)
			(layer "B.Fab")
			(hide yes)
			(effects
				(font
					(size 1 1)
					(thickness 0.15)
				)
				(justify mirror)
			)
		)
		(property "License" "Apache-2.0"
			(at 0 0 0)
			(layer "B.Fab")
			(hide yes)
			(effects
				(font
					(size 1 1)
					(thickness 0.15)
				)
				(justify mirror)
			)
		)
		(property "MPN" "CR0402-FX-1002GLF"
			(at 0 0 0)
			(layer "B.Fab")
			(hide yes)
			(effects
				(font
					(size 1 1)
					(thickness 0.15)
				)
				(justify mirror)
			)
		)
		(property "Manufacturer" "Bourns"
			(at 0 0 0)
			(layer "B.Fab")
			(hide yes)
			(effects
				(font
					(size 1 1)
					(thickness 0.15)
				)
				(justify mirror)
			)
		)
		(property "Public" "False"
			(at 0 0 0)
			(layer "B.Fab")
			(hide yes)
			(effects
				(font
					(size 1 1)
					(thickness 0.15)
				)
				(justify mirror)
			)
		)
		(property "Tolerance" "1%"
			(at 0 0 0)
			(layer "B.Fab")
			(hide yes)
			(effects
				(font
					(size 1 1)
					(thickness 0.15)
				)
				(justify mirror)
			)
		)
		(property "Val" "10k"
			(at 0 0 0)
			(layer "B.Fab")
			(hide yes)
			(effects
				(font
					(size 1 1)
					(thickness 0.15)
				)
				(justify mirror)
			)
		)
		(sheetname "OCuLink")
		(sheetfile "oculink.kicad_sch")
		(attr smd dnp)
		(fp_rect
			(start -0.925 0.47)
			(end 0.925 -0.47)
			(stroke
				(width 0.05)
				(type default)
			)
			(fill no)
			(layer "B.CrtYd")
		)
		(fp_rect
			(start -0.5 0.25)
			(end 0.5 -0.25)
			(stroke
				(width 0.15)
				(type solid)
			)
			(fill no)
			(layer "B.Fab")
		)
		(pad "1" smd roundrect
			(at -0.48 0)
			(size 0.59 0.64)
			(layers "B.Cu" "B.Mask" "B.Paste")
			(roundrect_rratio 0.25)
			(net 200 "/OCuLink/~{PERST_D0}")
			(pintype "passive")
			(teardrops
				(best_length_ratio 0.2)
				(max_length 1)
				(best_width_ratio 0.9)
				(max_width 2)
				(curved_edges yes)
				(filter_ratio 0.9)
				(enabled yes)
				(allow_two_segments yes)
				(prefer_zone_connections yes)
			)
		)
		(pad "2" smd roundrect
			(at 0.48 0)
			(size 0.59 0.64)
			(layers "B.Cu" "B.Mask" "B.Paste")
			(roundrect_rratio 0.25)
			(net 2 "+3V3")
			(pintype "passive")
			(teardrops
				(best_length_ratio 0.2)
				(max_length 1)
				(best_width_ratio 0.9)
				(max_width 2)
				(curved_edges yes)
				(filter_ratio 0.9)
				(enabled yes)
				(allow_two_segments yes)
				(prefer_zone_connections yes)
			)
		)
	)
	(footprint "antmicro-footprints:C_0402_1005Metric"
		(layer "B.Cu")
		(at 311.274999 121.96 -90)
		(descr "Capacitor SMD 0402")
		(tags "capacitor SMD 0402")
		(property "Reference" "C44"
			(at 0.8 -0.425001 90)
			(layer "B.SilkS")
			(effects
				(font
					(size 0.7 0.7)
					(thickness 0.15)
				)
				(justify left bottom mirror)
			)
		)
		(property "Value" "C_1u_0402"
			(at -1.022927 -2.155213 90)
			(layer "B.Fab")
			(effects
				(font
					(size 0.7 0.7)
					(thickness 0.15)
				)
				(justify left bottom mirror)
			)
		)
		(property "Datasheet" "https://product.tdk.com/en/search/capacitor/ceramic/mlcc/info?part_no=C1005X6S1A105K050BC"
			(at 0 0 270)
			(layer "F.Fab")
			(hide yes)
			(effects
				(font
					(size 1.27 1.27)
					(thickness 0.15)
				)
			)
		)
		(property "Author" "Antmicro"
			(at 189.314999 433.234999 0)
			(layer "B.Fab")
			(hide yes)
			(effects
				(font
					(size 1 1)
					(thickness 0.15)
				)
				(justify mirror)
			)
		)
		(property "Dielectric" ""
			(at 189.314999 433.234999 0)
			(layer "B.Fab")
			(hide yes)
			(effects
				(font
					(size 1 1)
					(thickness 0.15)
				)
				(justify mirror)
			)
		)
		(property "License" "Apache-2.0"
			(at 189.314999 433.234999 0)
			(layer "B.Fab")
			(hide yes)
			(effects
				(font
					(size 1 1)
					(thickness 0.15)
				)
				(justify mirror)
			)
		)
		(property "MPN" "C1005X6S1A105K050BC"
			(at 189.314999 433.234999 0)
			(layer "B.Fab")
			(hide yes)
			(effects
				(font
					(size 1 1)
					(thickness 0.15)
				)
				(justify mirror)
			)
		)
		(property "Manufacturer" "TDK"
			(at 189.314999 433.234999 0)
			(layer "B.Fab")
			(hide yes)
			(effects
				(font
					(size 1 1)
					(thickness 0.15)
				)
				(justify mirror)
			)
		)
		(property "Public" "False"
			(at 189.314999 433.234999 0)
			(layer "B.Fab")
			(hide yes)
			(effects
				(font
					(size 1 1)
					(thickness 0.15)
				)
				(justify mirror)
			)
		)
		(property "Val" "1u"
			(at 189.314999 433.234999 0)
			(layer "B.Fab")
			(hide yes)
			(effects
				(font
					(size 1 1)
					(thickness 0.15)
				)
				(justify mirror)
			)
		)
		(property "Voltage" ""
			(at 189.314999 433.234999 0)
			(layer "B.Fab")
			(hide yes)
			(effects
				(font
					(size 1 1)
					(thickness 0.15)
				)
				(justify mirror)
			)
		)
		(sheetname "Power")
		(sheetfile "power.kicad_sch")
		(attr smd)
		(fp_rect
			(start -0.925 0.47)
			(end 0.925 -0.47)
			(stroke
				(width 0.05)
				(type default)
			)
			(fill no)
			(layer "B.CrtYd")
		)
		(fp_line
			(start -0.494 0.25)
			(end -0.494 -0.248)
			(stroke
				(width 0.15)
				(type solid)
			)
			(layer "B.Fab")
		)
		(fp_line
			(start 0.504 0.25)
			(end -0.494 0.25)
			(stroke
				(width 0.15)
				(type solid)
			)
			(layer "B.Fab")
		)
		(fp_line
			(start -0.494 -0.248)
			(end 0.504 -0.248)
			(stroke
				(width 0.15)
				(type solid)
			)
			(layer "B.Fab")
		)
		(fp_line
			(start 0.504 -0.248)
			(end 0.504 0.25)
			(stroke
				(width 0.15)
				(type solid)
			)
			(layer "B.Fab")
		)
		(pad "1" smd roundrect
			(at -0.48 0 270)
			(size 0.59 0.64)
			(layers "B.Cu" "B.Mask" "B.Paste")
			(roundrect_rratio 0.25)
			(net 1 "GND")
			(pintype "passive")
			(teardrops
				(best_length_ratio 0.2)
				(max_length 1)
				(best_width_ratio 0.9)
				(max_width 2)
				(curved_edges yes)
				(filter_ratio 0.9)
				(enabled yes)
				(allow_two_segments yes)
				(prefer_zone_connections yes)
			)
		)
		(pad "2" smd roundrect
			(at 0.48 0 270)
			(size 0.59 0.64)
			(layers "B.Cu" "B.Mask" "B.Paste")
			(roundrect_rratio 0.25)
			(net 63 "Net-(U18-V_{CC})")
			(pintype "passive")
			(teardrops
				(best_length_ratio 0.2)
				(max_length 1)
				(best_width_ratio 0.9)
				(max_width 2)
				(curved_edges yes)
				(filter_ratio 0.9)
				(enabled yes)
				(allow_two_segments yes)
				(prefer_zone_connections yes)
			)
		)
	)
	(footprint "antmicro-footprints:R_0402_1005Metric"
		(layer "B.Cu")
		(at 144.25 142.06)
		(descr "Resistor SMD 0402")
		(tags "resistor SMD 0402")
		(property "Reference" "R269"
			(at -1.45 5.4 0)
			(layer "B.SilkS")
			(effects
				(font
					(size 0.7 0.7)
					(thickness 0.15)
				)
				(justify right bottom mirror)
			)
		)
		(property "Value" "R_10k_0402"
			(at -1.011843 -1.772047 0)
			(layer "B.Fab")
			(effects
				(font
					(size 0.7 0.7)
					(thickness 0.15)
				)
				(justify right bottom mirror)
			)
		)
		(property "Datasheet" "https://www.bourns.com/docs/product-datasheets/cr.pdf"
			(at 0 0 0)
			(layer "F.Fab")
			(hide yes)
			(effects
				(font
					(size 1.27 1.27)
					(thickness 0.15)
				)
			)
		)
		(property "Author" "Antmicro"
			(at 0 0 0)
			(layer "B.Fab")
			(hide yes)
			(effects
				(font
					(size 1 1)
					(thickness 0.15)
				)
				(justify mirror)
			)
		)
		(property "License" "Apache-2.0"
			(at 0 0 0)
			(layer "B.Fab")
			(hide yes)
			(effects
				(font
					(size 1 1)
					(thickness 0.15)
				)
				(justify mirror)
			)
		)
		(property "MPN" "CR0402-FX-1002GLF"
			(at 0 0 0)
			(layer "B.Fab")
			(hide yes)
			(effects
				(font
					(size 1 1)
					(thickness 0.15)
				)
				(justify mirror)
			)
		)
		(property "Manufacturer" "Bourns"
			(at 0 0 0)
			(layer "B.Fab")
			(hide yes)
			(effects
				(font
					(size 1 1)
					(thickness 0.15)
				)
				(justify mirror)
			)
		)
		(property "Public" "False"
			(at 0 0 0)
			(layer "B.Fab")
			(hide yes)
			(effects
				(font
					(size 1 1)
					(thickness 0.15)
				)
				(justify mirror)
			)
		)
		(property "Tolerance" "1%"
			(at 0 0 0)
			(layer "B.Fab")
			(hide yes)
			(effects
				(font
					(size 1 1)
					(thickness 0.15)
				)
				(justify mirror)
			)
		)
		(property "Val" "10k"
			(at 0 0 0)
			(layer "B.Fab")
			(hide yes)
			(effects
				(font
					(size 1 1)
					(thickness 0.15)
				)
				(justify mirror)
			)
		)
		(sheetname "KR to SFI #1")
		(sheetfile "kr_sfi.kicad_sch")
		(attr smd)
		(fp_rect
			(start -0.925 0.47)
			(end 0.925 -0.47)
			(stroke
				(width 0.05)
				(type default)
			)
			(fill no)
			(layer "B.CrtYd")
		)
		(fp_rect
			(start -0.5 0.25)
			(end 0.5 -0.25)
			(stroke
				(width 0.15)
				(type solid)
			)
			(fill no)
			(layer "B.Fab")
		)
		(pad "1" smd roundrect
			(at -0.48 0)
			(size 0.59 0.64)
			(layers "B.Cu" "B.Mask" "B.Paste")
			(roundrect_rratio 0.25)
			(net 1 "GND")
			(pintype "passive")
			(teardrops
				(best_length_ratio 0.2)
				(max_length 1)
				(best_width_ratio 0.9)
				(max_width 2)
				(curved_edges yes)
				(filter_ratio 0.9)
				(enabled yes)
				(allow_two_segments yes)
				(prefer_zone_connections yes)
			)
		)
		(pad "2" smd roundrect
			(at 0.48 0)
			(size 0.59 0.64)
			(layers "B.Cu" "B.Mask" "B.Paste")
			(roundrect_rratio 0.25)
			(net 662 "Net-(U43C-MODE_{SEL})")
			(pintype "passive")
			(teardrops
				(best_length_ratio 0.2)
				(max_length 1)
				(best_width_ratio 0.9)
				(max_width 2)
				(curved_edges yes)
				(filter_ratio 0.9)
				(enabled yes)
				(allow_two_segments yes)
				(prefer_zone_connections yes)
			)
		)
	)
	(footprint "antmicro-footprints:SOT-23-3"
		(layer "B.Cu")
		(at 306.525 101.76 -90)
		(property "Reference" "D36"
			(at -1.8 1.8 90)
			(layer "B.SilkS")
			(effects
				(font
					(size 0.7 0.7)
					(thickness 0.15)
				)
				(justify left bottom mirror)
			)
		)
		(property "Value" "BAT54C"
			(at -1.9 -2.7 90)
			(layer "B.Fab")
			(effects
				(font
					(size 0.7 0.7)
					(thickness 0.15)
				)
				(justify left bottom mirror)
			)
		)
		(property "Datasheet" "https://diotec.com/request/datasheet/bat54.pdf"
			(at 0 0 90)
			(layer "B.Fab")
			(hide yes)
			(effects
				(font
					(size 1.27 1.27)
					(thickness 0.15)
				)
				(justify mirror)
			)
		)
		(property "MPN" "BAT54C"
			(at 0 0 90)
			(unlocked yes)
			(layer "B.Fab")
			(hide yes)
			(effects
				(font
					(size 1 1)
					(thickness 0.15)
				)
				(justify mirror)
			)
		)
		(property "Manufacturer" "Diotec Semiconductor"
			(at 0 0 90)
			(unlocked yes)
			(layer "B.Fab")
			(hide yes)
			(effects
				(font
					(size 1 1)
					(thickness 0.15)
				)
				(justify mirror)
			)
		)
		(property "Author" "Antmicro"
			(at 0 0 90)
			(unlocked yes)
			(layer "B.Fab")
			(hide yes)
			(effects
				(font
					(size 1 1)
					(thickness 0.15)
				)
				(justify mirror)
			)
		)
		(property "License" "Apache-2.0"
			(at 0 0 90)
			(unlocked yes)
			(layer "B.Fab")
			(hide yes)
			(effects
				(font
					(size 1 1)
					(thickness 0.15)
				)
				(justify mirror)
			)
		)
		(sheetname "Power")
		(sheetfile "power.kicad_sch")
		(attr smd)
		(fp_line
			(start -0.7 1.5)
			(end 0.7 1.5)
			(stroke
				(width 0.15)
				(type solid)
			)
			(layer "B.SilkS")
		)
		(fp_line
			(start -0.7 1.5)
			(end -0.85 1.35)
			(stroke
				(width 0.15)
				(type solid)
			)
			(layer "B.SilkS")
		)
		(fp_line
			(start 0.7 1.5)
			(end 0.7 0.4)
			(stroke
				(width 0.15)
				(type solid)
			)
			(layer "B.SilkS")
		)
		(fp_line
			(start -0.85 1.35)
			(end -1.45 1.35)
			(stroke
				(width 0.15)
				(type solid)
			)
			(layer "B.SilkS")
		)
		(fp_line
			(start -0.7 -1.35)
			(end -0.7 -1.5)
			(stroke
				(width 0.15)
				(type solid)
			)
			(layer "B.SilkS")
		)
		(fp_line
			(start -0.7 -1.5)
			(end 0.7 -1.5)
			(stroke
				(width 0.15)
				(type solid)
			)
			(layer "B.SilkS")
		)
		(fp_line
			(start 0.7 -1.5)
			(end 0.7 -0.4)
			(stroke
				(width 0.15)
				(type solid)
			)
			(layer "B.SilkS")
		)
		(fp_line
			(start 0.825 1.6)
			(end -0.9 1.6)
			(stroke
				(width 0.05)
				(type solid)
			)
			(layer "B.CrtYd")
		)
		(fp_line
			(start -1.75 1.4)
			(end -0.9 1.4)
			(stroke
				(width 0.05)
				(type solid)
			)
			(layer "B.CrtYd")
		)
		(fp_line
			(start -1.75 1.4)
			(end -1.75 0.5)
			(stroke
				(width 0.05)
				(type solid)
			)
			(layer "B.CrtYd")
		)
		(fp_line
			(start -0.9 1.4)
			(end -0.9 1.6)
			(stroke
				(width 0.05)
				(type solid)
			)
			(layer "B.CrtYd")
		)
		(fp_line
			(start -1.75 0.5)
			(end -0.85 0.5)
			(stroke
				(width 0.05)
				(type solid)
			)
			(layer "B.CrtYd")
		)
		(fp_line
			(start -0.85 0.5)
			(end -0.85 -0.5)
			(stroke
				(width 0.05)
				(type solid)
			)
			(layer "B.CrtYd")
		)
		(fp_line
			(start 0.825 0.45)
			(end 0.825 1.6)
			(stroke
				(width 0.05)
				(type solid)
			)
			(layer "B.CrtYd")
		)
		(fp_line
			(start 1.75 0.45)
			(end 0.825 0.45)
			(stroke
				(width 0.05)
				(type solid)
			)
			(layer "B.CrtYd")
		)
		(fp_line
			(start 0.85 -0.45)
			(end 1.75 -0.45)
			(stroke
				(width 0.05)
				(type solid)
			)
			(layer "B.CrtYd")
		)
		(fp_line
			(start 1.75 -0.45)
			(end 1.75 0.45)
			(stroke
				(width 0.05)
				(type solid)
			)
			(layer "B.CrtYd")
		)
		(fp_line
			(start -1.75 -0.5)
			(end -1.75 -1.4)
			(stroke
				(width 0.05)
				(type solid)
			)
			(layer "B.CrtYd")
		)
		(fp_line
			(start -0.85 -0.5)
			(end -1.75 -0.5)
			(stroke
				(width 0.05)
				(type solid)
			)
			(layer "B.CrtYd")
		)
		(fp_line
			(start -1.75 -1.4)
			(end -0.85 -1.4)
			(stroke
				(width 0.05)
				(type solid)
			)
			(layer "B.CrtYd")
		)
		(fp_line
			(start -0.85 -1.4)
			(end -0.85 -1.65)
			(stroke
				(width 0.05)
				(type solid)
			)
			(layer "B.CrtYd")
		)
		(fp_line
			(start -0.85 -1.65)
			(end 0.85 -1.65)
			(stroke
				(width 0.05)
				(type solid)
			)
			(layer "B.CrtYd")
		)
		(fp_line
			(start 0.85 -1.65)
			(end 0.85 -0.45)
			(stroke
				(width 0.05)
				(type solid)
			)
			(layer "B.CrtYd")
		)
		(fp_line
			(start 0.688 1.526)
			(end -0.437 1.526)
			(stroke
				(width 0.15)
				(type solid)
			)
			(layer "B.Fab")
		)
		(fp_line
			(start 0.688 1.52)
			(end 0.688 -1.519)
			(stroke
				(width 0.15)
				(type solid)
			)
			(layer "B.Fab")
		)
		(fp_line
			(start -0.712 1.325)
			(end -0.437 1.526)
			(stroke
				(width 0.15)
				(type solid)
			)
			(layer "B.Fab")
		)
		(fp_line
			(start 0.688 -1.519)
			(end -0.712 -1.519)
			(stroke
				(width 0.15)
				(type solid)
			)
			(layer "B.Fab")
		)
		(fp_line
			(start -0.712 -1.523)
			(end -0.712 1.325)
			(stroke
				(width 0.15)
				(type solid)
			)
			(layer "B.Fab")
		)
		(pad "1" smd roundrect
			(at -1.1 0.951 270)
			(size 1 0.6)
			(layers "B.Cu" "B.Mask" "B.Paste")
			(roundrect_rratio 0.15)
			(net 574 "Net-(U19-EN)")
			(pinfunction "1")
			(pintype "passive")
			(teardrops
				(best_length_ratio 0.2)
				(max_length 1)
				(best_width_ratio 0.9)
				(max_width 2)
				(curved_edges yes)
				(filter_ratio 0.9)
				(enabled yes)
				(allow_two_segments yes)
				(prefer_zone_connections yes)
			)
		)
		(pad "2" smd roundrect
			(at -1.1 -0.949 270)
			(size 1 0.6)
			(layers "B.Cu" "B.Mask" "B.Paste")
			(roundrect_rratio 0.15)
			(net 574 "Net-(U19-EN)")
			(pinfunction "2")
			(pintype "passive")
			(teardrops
				(best_length_ratio 0.2)
				(max_length 1)
				(best_width_ratio 0.9)
				(max_width 2)
				(curved_edges yes)
				(filter_ratio 0.9)
				(enabled yes)
				(allow_two_segments yes)
				(prefer_zone_connections yes)
			)
		)
		(pad "3" smd roundrect
			(at 1.1 0.0005 270)
			(size 1 0.6)
			(layers "B.Cu" "B.Mask" "B.Paste")
			(roundrect_rratio 0.15)
			(net 533 "/Com Express 7 MGMT/PSON")
			(pinfunction "3")
			(pintype "passive")
			(teardrops
				(best_length_ratio 0.2)
				(max_length 1)
				(best_width_ratio 0.9)
				(max_width 2)
				(curved_edges yes)
				(filter_ratio 0.9)
				(enabled yes)
				(allow_two_segments yes)
				(prefer_zone_connections yes)
			)
		)
	)
)
